#ISCELL
  mstr_misc dns *
  *
#ISCELL
  mstr_symbols design_note *
  *
#ISCELL
  mstr_symbols intel_corp_bpage *
  *
#ISCELL
  mstr_standard offpage *
  page215_i1
#ISCELL
  mstr_standard offpage *
  page215_i10
#ISCELL
  mstr_standard offpage *
  page215_i11
#CELL
  mstr_discrete res *
  page215_i12
#CELL
  mstr_discrete res *
  page215_i13
#CELL
  mstr_discrete cap *
  page215_i14
#CELL
  mstr_discrete res *
  page215_i15
#CELL
  w_hdl sc22p50v2jn-4gp *
  page215_i16
#ISCELL
  mstr_symbols pvccio_cpu0 *
  page215_i18
#ISCELL
  mstr_symbols gnd *
  page215_i19
#ISCELL
  mstr_standard offpage *
  page215_i2
#ISCELL
  mstr_symbols gnd *
  page215_i20
#CELL
  mstr_discrete cap *
  page215_i22
#ISCELL
  mstr_symbols gnd *
  page215_i23
#ISCELL
  mstr_symbols gnd *
  page215_i24
#CELL
  w_hdl sc22p50v2jn-4gp *
  page215_i26
#CELL
  mstr_discrete res *
  page215_i27
#CELL
  mstr_discrete res *
  page215_i28
#CELL
  mstr_discrete res *
  page215_i29
#ISCELL
  mstr_standard offpage *
  page215_i3
#ISCELL
  mstr_symbols p3v3_stby *
  page215_i30
#ISCELL
  mstr_symbols gnd *
  page215_i31
#ISCELL
  mstr_symbols gnd *
  page215_i32
#CELL
  mstr_discrete res *
  page215_i33
#CELL
  dev_discrete cap_a *
  page215_i34
#CELL
  dev_discrete cap_a *
  page215_i35
#ISCELL
  mstr_symbols gnd *
  page215_i36
#ISCELL
  mstr_symbols gnd *
  page215_i37
#CELL
  dev_discrete cap_a *
  page215_i38
#ISCELL
  mstr_symbols gnd *
  page215_i39
#ISCELL
  mstr_standard offpage *
  page215_i4
#CELL
  dev_discrete cap_a *
  page215_i40
#CELL
  mstr_discrete res *
  page215_i41
#ISCELL
  mstr_standard offpage *
  page215_i42
#ISCELL
  mstr_symbols gnd *
  page215_i43
#CELL
  mstr_discrete cap *
  page215_i44
#CELL
  mstr_discrete res *
  page215_i45
#CELL
  mstr_discrete res *
  page215_i49
#ISCELL
  mstr_standard offpage *
  page215_i5
#CELL
  mstr_discrete res *
  page215_i50
#CELL
  mstr_discrete res *
  page215_i51
#ISCELL
  mstr_symbols p3v3_stby *
  page215_i52
#CELL
  mstr_discrete res *
  page215_i53
#CELL
  mstr_discrete res *
  page215_i54
#ISCELL
  mstr_standard offpage *
  page215_i55
#CELL
  mstr_discrete res *
  page215_i56
#CELL
  mstr_discrete res *
  page215_i58
#ISCELL
  mstr_symbols pvccio_cpu0 *
  page215_i59
#ISCELL
  mstr_standard offpage *
  page215_i6
#ISCELL
  mstr_standard offpage *
  page215_i60
#ISCELL
  mstr_standard offpage *
  page215_i61
#ISCELL
  mstr_standard offpage *
  page215_i62
#ISCELL
  mstr_standard offpage *
  page215_i63
#ISCELL
  mstr_standard offpage *
  page215_i64
#ISCELL
  mstr_standard offpage *
  page215_i65
#ISCELL
  mstr_standard offpage *
  page215_i66
#ISCELL
  mstr_standard offpage *
  page215_i67
#ISCELL
  mstr_standard offpage *
  page215_i68
#CELL
  mstr_controller pxm1310b *
  page215_i69
#ISCELL
  mstr_standard offpage *
  page215_i7
#CELL
  mstr_discrete res *
  page215_i70
#CELL
  mstr_discrete res *
  page215_i72
#CELL
  mstr_discrete res *
  page215_i73
#CELL
  mstr_discrete res *
  page215_i74
#CELL
  mstr_discrete res *
  page215_i75
#ISCELL
  mstr_standard offpage *
  page215_i8
#ISCELL
  mstr_standard offpage *
  page215_i9
